FILE_TYPE = CONNECTIVITY;
{Allegro Design Entry HDL 16.6-p007 (v16-6-112F) 10/10/2012}
"PAGE_NUMBER" = 46;
0"NC";
1"M_B_ECC<7:0>";
2"M_B_DQ<63:0>";
3"M_B_CLK_DN<3:0>";
4"M_B_ODT<3:0>";
5"M_B_CKE<3:0>";
6"M_B_CS_N<7:0>";
7"M_B_CLK_DP<3:0>";
8"M_B_BA<1:0>";
9"M_B_BG<1:0>";
10"M_B_MA<17:0>";
11"M_B_DQS_DN<17:0>";
12"M_B_DQS_DP<17:0>";
13"GND\g";
14"PVDDQ_ABC\g";
15"PVTT_ABC\g";
16"PVPP_ABC\g";
17"GND\g";
18"GND\g";
19"P12V_NVDIMM_ABC\g";
20"GND\g";
21"PVPP_ABC\g";
22"M_B_DQ<55>";
23"M_B_DQS_DN<8>";
24"M_B_DQ<9>";
25"M_B_DQ<54>";
26"M_B_DQS_DP<9>";
27"M_B_DQS_DN<7>";
28"M_B_DQS_DN<6>";
29"M_B_DQS_DN<5>";
30"M_B_DQS_DN<4>";
31"M_B_DQS_DP<3>";
32"M_B_DQS_DN<16>";
33"M_B_DQS_DN<17>";
34"M_B_DQS_DP<16>";
35"M_B_DQS_DP<17>";
36"M_B_DQS_DN<11>";
37"M_B_DQS_DN<12>";
38"M_B_DQS_DN<13>";
39"M_B_DQS_DN<14>";
40"M_B_DQS_DN<15>";
41"M_B_DQS_DP<13>";
42"M_B_DQS_DP<14>";
43"M_B_DQS_DP<15>";
44"M_B_DQS_DP<10>";
45"M_B_DQS_DP<11>";
46"M_B_DQS_DP<12>";
47"M_B_DQS_DN<10>";
48"M_B_DQS_DN<9>";
49"M_B_DQS_DP<8>";
50"M_B_DQS_DP<5>";
51"M_B_DQS_DP<6>";
52"M_B_DQS_DP<7>";
53"M_B_DQS_DN<1>";
54"M_B_DQS_DN<2>";
55"M_B_DQS_DN<3>";
56"M_B_DQS_DP<4>";
57"M_B_DQS_DP<0>";
58"M_B_DQS_DP<1>";
59"M_B_DQS_DP<2>";
60"M_B_DQS_DN<0>";
61"M_B_DQ<63>";
62"M_B_DQ<62>";
63"M_B_DQ<61>";
64"M_B_DQ<60>";
65"M_B_MA<17>";
66"M_B_MA<14>";
67"M_B_MA<15>";
68"M_B_MA<16>";
69"M_B_DQ<59>";
70"M_B_DQ<56>";
71"M_B_DQ<57>";
72"M_B_DQ<58>";
73"M_B_DQ<53>";
74"M_B_DQ<52>";
75"M_B_DQ<51>";
76"M_B_DQ<50>";
77"M_B_DQ<46>";
78"M_B_DQ<45>";
79"M_B_DQ<44>";
80"M_B_DQ<43>";
81"M_B_DQ<42>";
82"M_B_DQ<41>";
83"M_B_DQ<40>";
84"M_B_DQ<49>";
85"M_B_DQ<48>";
86"M_B_DQ<47>";
87"M_B_DQ<39>";
88"M_B_DQ<37>";
89"M_B_DQ<34>";
90"M_B_DQ<33>";
91"M_B_DQ<32>";
92"M_B_DQ<31>";
93"M_B_DQ<30>";
94"M_B_DQ<35>";
95"M_B_DQ<36>";
96"M_B_DQ<38>";
97"M_B_DQ<29>";
98"M_B_DQ<28>";
99"M_B_DQ<25>";
100"M_B_DQ<24>";
101"M_B_DQ<23>";
102"M_B_DQ<22>";
103"M_B_DQ<21>";
104"M_B_DQ<20>";
105"M_B_DQ<19>";
106"M_B_DQ<27>";
107"M_B_DQ<26>";
108"M_B_MA<12>";
109"M_B_MA<13>";
110"M_B_MA<9>";
111"M_B_MA<10>";
112"M_B_MA<11>";
113"M_B_MA<4>";
114"M_B_MA<6>";
115"M_B_MA<7>";
116"M_B_MA<8>";
117"M_B_MA<5>";
118"M_B_MA<0>";
119"M_B_MA<1>";
120"M_B_MA<3>";
121"M_B_MA<2>";
122"M_B_BA<1>";
123"M_B_BG<0>";
124"M_B_BG<1>";
125"M_B_BA<0>";
126"M_B_CLK_DP<2>";
127"M_B_CLK_DP<3>";
128"M_B_C<2>";
129"M_B_CS_N<7>";
130"M_B_CS_N<6>";
131"M_B_CS_N<5>";
132"M_B_CS_N<4>";
133"M_B_CKE<3>";
134"M_B_ODT<3>";
135"M_B_CKE<2>";
136"M_B_ODT<2>";
137"M_B_ECC<6>";
138"M_B_ECC<5>";
139"M_B_ECC<4>";
140"M_B_ECC<7>";
141"M_B_CLK_DN<3>";
142"M_B_CLK_DN<2>";
143"M_ABC_RST_N";
144"M_B_PAR";
145"M_B_DQ<18>";
146"M_B_DQ<16>";
147"M_B_DQ<14>";
148"M_B_DQ<13>";
149"M_B_DQ<12>";
150"M_B_DQ<11>";
151"M_B_DQ<10>";
152"M_B_DQ<15>";
153"M_B_DQ<17>";
154"M_B_DQ<1>";
155"M_B_DQ<8>";
156"M_B_DQ<7>";
157"M_B_DQ<6>";
158"M_B_DQ<0>";
159"M_B_DQ<2>";
160"M_B_DQ<3>";
161"M_B_DQ<4>";
162"M_B_DQ<5>";
163"M_B_ECC<3>";
164"M_B_ECC<2>";
165"M_B_ECC<1>";
166"M_B_ECC<0>";
167"FM_DIMM_EVENT_COD_N";
168"M_B_ACT_N";
169"M_B_ALERT_N";
170"SMB_DDR_ABC_VPP_SDA";
171"SMB_DDR_ABC_VPP_SCL";
172"FM_ADR_COMPLETE_ABC_N";
173"TP_CH_B_DIMM_B1_RFU_2";
174"TP_CH_B_DIMM_B1_RFU_0";
175"TP_CH_B_DIMM_B1_RFU_1";
176"M_B_VREF";
%"GND"
"1","(-2975,650)","0","mstr_symbols","I1";
;
HDL_POWER"GND"
ROOM"DDR4_CH_A"
BODY_TYPE"PLUMBING"
CDS_LIB"mstr_symbols"
SIZE"1B"
BOM_COST"MEM"
VOLTAGE"0";
"A\NAC"13;
%"TAP"
"6","(-75,3250)","2","mstr_standard","I100";
;
HDL_TAP"TRUE"
BODY_TYPE"PLUMBING"
CDS_LIB"mstr_standard";
"B \NAC \NWC"2;
"S \NAC"
BN"43"80;
%"TAP"
"6","(-75,3350)","2","mstr_standard","I101";
;
HDL_TAP"TRUE"
BODY_TYPE"PLUMBING"
CDS_LIB"mstr_standard";
"B \NAC \NWC"2;
"S \NAC"
BN"45"78;
%"TAP"
"6","(-75,3450)","2","mstr_standard","I102";
;
HDL_TAP"TRUE"
BODY_TYPE"PLUMBING"
CDS_LIB"mstr_standard";
"B \NAC \NWC"2;
"S \NAC"
BN"47"86;
%"TAP"
"6","(-75,3400)","2","mstr_standard","I103";
;
HDL_TAP"TRUE"
BODY_TYPE"PLUMBING"
CDS_LIB"mstr_standard";
"B \NAC \NWC"2;
"S \NAC"
BN"46"77;
%"TAP"
"6","(-75,3550)","2","mstr_standard","I104";
;
HDL_TAP"TRUE"
BODY_TYPE"PLUMBING"
CDS_LIB"mstr_standard";
"B \NAC \NWC"2;
"S \NAC"
BN"49"84;
%"TAP"
"6","(-75,3500)","2","mstr_standard","I105";
;
HDL_TAP"TRUE"
BODY_TYPE"PLUMBING"
CDS_LIB"mstr_standard";
"B \NAC \NWC"2;
"S \NAC"
BN"48"85;
%"TAP"
"6","(-75,3600)","2","mstr_standard","I106";
;
HDL_TAP"TRUE"
BODY_TYPE"PLUMBING"
CDS_LIB"mstr_standard";
"B \NAC \NWC"2;
"S \NAC"
BN"50"76;
%"TAP"
"6","(-75,3650)","2","mstr_standard","I107";
;
HDL_TAP"TRUE"
BODY_TYPE"PLUMBING"
CDS_LIB"mstr_standard";
"B \NAC \NWC"2;
"S \NAC"
BN"51"75;
%"TAP"
"6","(-75,3700)","2","mstr_standard","I108";
;
HDL_TAP"TRUE"
BODY_TYPE"PLUMBING"
CDS_LIB"mstr_standard";
"B \NAC \NWC"2;
"S \NAC"
BN"52"74;
%"PVDDQ_ABC"
"1","(600,2200)","0","mstr_symbols","I109";
;
HDL_POWER"PVDDQ_ABC"
ROOM"DDR4_CH_A"
BODY_TYPE"PLUMBING"
CDS_LIB"mstr_symbols"
BOM_COST"MEM"
VOLTAGE"1.2V";
"G\NAC"14;
%"PVTT_ABC"
"1","(825,2350)","0","mstr_symbols","I110";
;
HDL_POWER"PVTT_ABC"
ROOM"DDR4_CH_A"
BODY_TYPE"PLUMBING"
CDS_LIB"mstr_symbols"
BOM_COST"MEM"
VOLTAGE"0.6V";
"G\NAC"15;
%"PVPP_ABC"
"1","(975,2650)","0","mstr_symbols","I111";
;
HDL_POWER"PVPP_ABC"
ROOM"DDR4_CH_A"
BODY_TYPE"PLUMBING"
CDS_LIB"mstr_symbols"
BOM_COST"MEM"
VOLTAGE"2.5V";
"G\NAC"16;
%"SCONN288_H44441003"
"2","(1625,3950)","0","mstr_sconn","I112";
;
CDS_SEC"2"
MATERIAL"SCONN"
PART_NUMBER"H44441-003"
LOCATION"J6U1"
BOM_SS"NOPOP"
ROOM"DDR4_CH_B"
CDS_LOCATION"J6U1"
SEC"2"
SEC_TYPE"PIP"
CDS_LIB"mstr_sconn"
BOM_COST"MEM"
PACK_TYPE"PIP";
"DQS0N"
$PN"152"60;
"DQS0P"
$PN"153"57;
"DQS10N"
$PN"19"47;
"DQS10P"
$PN"18"44;
"DQS11N"
$PN"30"36;
"DQS11P"
$PN"29"45;
"DQS12N"
$PN"41"37;
"DQS12P"
$PN"40"46;
"DQS13N"
$PN"100"38;
"DQS13P"
$PN"99"41;
"DQS14N"
$PN"111"39;
"DQS14P"
$PN"110"42;
"DQS15N"
$PN"122"40;
"DQS15P"
$PN"121"43;
"DQS16N"
$PN"133"32;
"DQS16P"
$PN"132"34;
"DQS17N"
$PN"52"33;
"DQS17P"
$PN"51"35;
"DQS1N"
$PN"163"53;
"DQS1P"
$PN"164"58;
"DQS2N"
$PN"174"54;
"DQS2P"
$PN"175"59;
"DQS3N"
$PN"185"55;
"DQS3P"
$PN"186"31;
"DQS4N"
$PN"244"30;
"DQS4P"
$PN"245"56;
"DQS5N"
$PN"255"29;
"DQS5P"
$PN"256"50;
"DQS6N"
$PN"266"28;
"DQS6P"
$PN"267"51;
"DQS7N"
$PN"277"27;
"DQS7P"
$PN"278"52;
"DQS8N"
$PN"196"23;
"DQS8P"
$PN"197"49;
"DQS9N"
$PN"8"48;
"DQS9P"
$PN"7"26;
%"TAP"
"6","(-1575,3750)","0","mstr_standard","I114";
;
HDL_TAP"TRUE"
BODY_TYPE"PLUMBING"
CDS_LIB"mstr_standard";
"B \NAC \NWC"10;
"S \NAC"
BN"7"115;
%"TAP"
"6","(-1575,3800)","0","mstr_standard","I115";
;
HDL_TAP"TRUE"
BODY_TYPE"PLUMBING"
CDS_LIB"mstr_standard";
"B \NAC \NWC"10;
"S \NAC"
BN"8"116;
%"TAP"
"6","(-1575,3950)","0","mstr_standard","I116";
;
HDL_TAP"TRUE"
BODY_TYPE"PLUMBING"
CDS_LIB"mstr_standard";
"B \NAC \NWC"10;
"S \NAC"
BN"11"112;
%"TAP"
"6","(-1575,3900)","0","mstr_standard","I117";
;
HDL_TAP"TRUE"
BODY_TYPE"PLUMBING"
CDS_LIB"mstr_standard";
"B \NAC \NWC"10;
"S \NAC"
BN"10"111;
%"TAP"
"6","(-1575,3850)","0","mstr_standard","I118";
;
HDL_TAP"TRUE"
BODY_TYPE"PLUMBING"
CDS_LIB"mstr_standard";
"B \NAC \NWC"10;
"S \NAC"
BN"9"110;
%"TAP"
"6","(-1575,4000)","0","mstr_standard","I119";
;
HDL_TAP"TRUE"
BODY_TYPE"PLUMBING"
CDS_LIB"mstr_standard";
"B \NAC \NWC"10;
"S \NAC"
BN"12"108;
%"TAP"
"6","(-1575,4050)","0","mstr_standard","I120";
;
HDL_TAP"TRUE"
BODY_TYPE"PLUMBING"
CDS_LIB"mstr_standard";
"B \NAC \NWC"10;
"S \NAC"
BN"13"109;
%"TAP"
"6","(-1575,4100)","0","mstr_standard","I121";
;
HDL_TAP"TRUE"
BODY_TYPE"PLUMBING"
CDS_LIB"mstr_standard";
"B \NAC \NWC"10;
"S \NAC"
BN"14"66;
%"TAP"
"6","(-1575,4200)","0","mstr_standard","I122";
;
HDL_TAP"TRUE"
BODY_TYPE"PLUMBING"
CDS_LIB"mstr_standard";
"B \NAC \NWC"10;
"S \NAC"
BN"16"68;
%"TAP"
"6","(-1575,4150)","0","mstr_standard","I123";
;
HDL_TAP"TRUE"
BODY_TYPE"PLUMBING"
CDS_LIB"mstr_standard";
"B \NAC \NWC"10;
"S \NAC"
BN"15"67;
%"TAP"
"6","(-1575,4250)","0","mstr_standard","I124";
;
HDL_TAP"TRUE"
BODY_TYPE"PLUMBING"
CDS_LIB"mstr_standard";
"B \NAC \NWC"10;
"S \NAC"
BN"17"65;
%"TAP"
"6","(-75,3750)","2","mstr_standard","I125";
;
HDL_TAP"TRUE"
BODY_TYPE"PLUMBING"
CDS_LIB"mstr_standard";
"B \NAC \NWC"2;
"S \NAC"
BN"53"73;
%"TAP"
"6","(-75,3850)","2","mstr_standard","I126";
;
HDL_TAP"TRUE"
BODY_TYPE"PLUMBING"
CDS_LIB"mstr_standard";
"B \NAC \NWC"2;
"S \NAC"
BN"55"22;
%"TAP"
"6","(-75,3800)","2","mstr_standard","I127";
;
HDL_TAP"TRUE"
BODY_TYPE"PLUMBING"
CDS_LIB"mstr_standard";
"B \NAC \NWC"2;
"S \NAC"
BN"54"25;
%"TAP"
"6","(-75,3950)","2","mstr_standard","I128";
;
HDL_TAP"TRUE"
BODY_TYPE"PLUMBING"
CDS_LIB"mstr_standard";
"B \NAC \NWC"2;
"S \NAC"
BN"57"71;
%"TAP"
"6","(-75,3900)","2","mstr_standard","I129";
;
HDL_TAP"TRUE"
BODY_TYPE"PLUMBING"
CDS_LIB"mstr_standard";
"B \NAC \NWC"2;
"S \NAC"
BN"56"70;
%"TAP"
"6","(-75,4000)","2","mstr_standard","I130";
;
HDL_TAP"TRUE"
BODY_TYPE"PLUMBING"
CDS_LIB"mstr_standard";
"B \NAC \NWC"2;
"S \NAC"
BN"58"72;
%"TAP"
"6","(-75,4050)","2","mstr_standard","I131";
;
HDL_TAP"TRUE"
BODY_TYPE"PLUMBING"
CDS_LIB"mstr_standard";
"B \NAC \NWC"2;
"S \NAC"
BN"59"69;
%"TAP"
"6","(-75,4100)","2","mstr_standard","I132";
;
HDL_TAP"TRUE"
BODY_TYPE"PLUMBING"
CDS_LIB"mstr_standard";
"B \NAC \NWC"2;
"S \NAC"
BN"60"64;
%"TAP"
"6","(-75,4150)","2","mstr_standard","I133";
;
HDL_TAP"TRUE"
BODY_TYPE"PLUMBING"
CDS_LIB"mstr_standard";
"B \NAC \NWC"2;
"S \NAC"
BN"61"63;
%"TAP"
"6","(-75,4200)","2","mstr_standard","I134";
;
HDL_TAP"TRUE"
BODY_TYPE"PLUMBING"
CDS_LIB"mstr_standard";
"B \NAC \NWC"2;
"S \NAC"
BN"62"62;
%"TAP"
"6","(-75,4250)","2","mstr_standard","I135";
;
HDL_TAP"TRUE"
BODY_TYPE"PLUMBING"
CDS_LIB"mstr_standard";
"B \NAC \NWC"2;
"S \NAC"
BN"63"61;
%"GND"
"1","(2725,950)","2","mstr_symbols","I137";
;
HDL_POWER"GND"
ROOM"DDR4_CH_A"
BODY_TYPE"PLUMBING"
BOM_COST"MEM"
CDS_LIB"mstr_symbols"
SIZE"1B"
VOLTAGE"0";
"A\NAC"17;
%"SCONN288_H44441003"
"3","(3425,2250)","0","mstr_sconn","I138";
;
CDS_SEC"3"
MATERIAL"SCONN"
LOCATION"J6U1"
PART_NUMBER"H44441-003"
BOM_SS"NOPOP"
ROOM"DDR4_CH_B"
CDS_LOCATION"J6U1"
SEC"3"
SEC_TYPE"PIP"
CDS_LIB"mstr_sconn"
BOM_COST"MEM"
PACK_TYPE"PIP";
"VSS<46>"
$PN"147"18;
"VSS<45>"
$PN"149"18;
"VSS<87>"
$PN"15"17;
"VSS<86>"
$PN"17"17;
"VSS<85>"
$PN"20"17;
"VSS<84>"
$PN"22"17;
"VSS<83>"
$PN"24"17;
"VSS<82>"
$PN"26"17;
"VSS<81>"
$PN"28"17;
"VSS<80>"
$PN"31"17;
"VSS<79>"
$PN"33"17;
"VSS<78>"
$PN"35"17;
"VSS<77>"
$PN"37"17;
"VSS<76>"
$PN"39"17;
"VSS<75>"
$PN"42"17;
"VSS<74>"
$PN"44"17;
"VSS<73>"
$PN"46"17;
"VSS<72>"
$PN"48"17;
"VSS<71>"
$PN"50"17;
"VSS<70>"
$PN"53"17;
"VSS<69>"
$PN"55"17;
"VSS<68>"
$PN"57"17;
"VSS<67>"
$PN"94"17;
"VSS<66>"
$PN"96"17;
"VSS<65>"
$PN"98"17;
"VSS<64>"
$PN"101"17;
"VSS<63>"
$PN"103"17;
"VSS<62>"
$PN"105"17;
"VSS<61>"
$PN"107"17;
"VSS<60>"
$PN"109"17;
"VSS<59>"
$PN"112"17;
"VSS<58>"
$PN"114"17;
"VSS<57>"
$PN"116"17;
"VSS<56>"
$PN"118"17;
"VSS<55>"
$PN"120"17;
"VSS<54>"
$PN"123"17;
"VSS<53>"
$PN"125"17;
"VSS<52>"
$PN"127"17;
"VSS<51>"
$PN"129"17;
"VSS<50>"
$PN"131"17;
"VSS<49>"
$PN"134"17;
"VSS<48>"
$PN"136"17;
"VSS<47>"
$PN"138"17;
"VSS<44>"
$PN"151"18;
"VSS<43>"
$PN"154"18;
"VSS<42>"
$PN"156"18;
"VSS<41>"
$PN"158"18;
"VSS<40>"
$PN"160"18;
"VSS<39>"
$PN"162"18;
"VSS<38>"
$PN"165"18;
"VSS<37>"
$PN"167"18;
"VSS<36>"
$PN"169"18;
"VSS<35>"
$PN"171"18;
"VSS<34>"
$PN"173"18;
"VSS<33>"
$PN"176"18;
"VSS<32>"
$PN"178"18;
"VSS<31>"
$PN"180"18;
"VSS<30>"
$PN"182"18;
"VSS<29>"
$PN"184"18;
"VSS<28>"
$PN"187"18;
"VSS<27>"
$PN"189"18;
"VSS<26>"
$PN"191"18;
"VSS<25>"
$PN"193"18;
"VSS<24>"
$PN"195"18;
"VSS<23>"
$PN"198"18;
"VSS<22>"
$PN"200"18;
"VSS<21>"
$PN"202"18;
"VSS<20>"
$PN"239"18;
"VSS<19>"
$PN"241"18;
"VSS<18>"
$PN"243"18;
"VSS<17>"
$PN"246"18;
"VSS<16>"
$PN"248"18;
"VSS<15>"
$PN"250"18;
"VSS<14>"
$PN"252"18;
"VSS<13>"
$PN"254"18;
"VSS<12>"
$PN"257"18;
"VSS<11>"
$PN"259"18;
"VSS<10>"
$PN"261"18;
"VSS<9>"
$PN"263"18;
"VSS<8>"
$PN"265"18;
"VSS<7>"
$PN"268"18;
"VSS<6>"
$PN"270"18;
"VSS<5>"
$PN"272"18;
"VSS<4>"
$PN"274"18;
"VSS<3>"
$PN"276"18;
"VSS<2>"
$PN"279"18;
"VSS<1>"
$PN"281"18;
"VSS<0>"
$PN"283"18;
"VSS<88>"
$PN"13"17;
"VSS<89>"
$PN"11"17;
"VSS<90>"
$PN"9"17;
"VSS<91>"
$PN"6"17;
"VSS<92>"
$PN"4"17;
"VSS<93>"
$PN"2"17;
%"SCONN288_H44441003"
"1","(-825,2600)","0","mstr_sconn","I14";
;
CDS_SEC"1"
PART_NUMBER"H44441-003"
LOCATION"J6U1"
MATERIAL"SCONN"
BOM_SS"NOPOP"
ROOM"DDR4_CH_B"
CDS_LOCATION"J6U1"
SEC"1"
SEC_TYPE"PIP"
CDS_LIB"mstr_sconn"
BOM_COST"MEM"
PACK_TYPE"PIP";
"DQ<63>"
$PN"280"61;
"BA<1>"
$PN"224"122;
"CK1N"
$PN"219"141;
"CK0P"
$PN"74"126;
"S3_N_C<1>"
$PN"237"129;
"S2_N_C<0>"
$PN"93"130;
"S1_N"
$PN"89"131;
"DQ<29>"
$PN"181"97;
"DQ<28>"
$PN"36"98;
"C<2>"
$PN"235"128;
"A0"
$PN"79"118;
"A1"
$PN"72"119;
"A12"
$PN"65"108;
"A13"
$PN"232"109;
"A17"
$PN"234"65;
"A3"
$PN"71"120;
"A4"
$PN"214"113;
"A5"
$PN"213"117;
"A6"
$PN"69"114;
"A7"
$PN"211"115;
"A8"
$PN"68"116;
"A9"
$PN"66"110;
"CB<6>"
$PN"54"137;
"CB<5>"
$PN"192"138;
"CB<4>"
$PN"47"139;
"CB<3>"
$PN"201"163;
"CB<2>"
$PN"56"164;
"CB<1>"
$PN"194"165;
"CB<0>"
$PN"49"166;
"CK0N"
$PN"75"142;
"CKE<1>"
$PN"203"133;
"DQ<62>"
$PN"135"62;
"DQ<61>"
$PN"273"63;
"DQ<60>"
$PN"128"64;
"DQ<59>"
$PN"282"69;
"DQ<56>"
$PN"130"70;
"DQ<55>"
$PN"269"22;
"DQ<46>"
$PN"113"77;
"DQ<45>"
$PN"251"78;
"DQ<44>"
$PN"106"79;
"DQ<43>"
$PN"260"80;
"DQ<42>"
$PN"115"81;
"DQ<41>"
$PN"253"82;
"DQ<40>"
$PN"108"83;
"DQ<39>"
$PN"247"87;
"DQ<37>"
$PN"240"88;
"DQ<34>"
$PN"104"89;
"DQ<33>"
$PN"242"90;
"DQ<32>"
$PN"97"91;
"DQ<31>"
$PN"188"92;
"DQ<30>"
$PN"43"93;
"DQ<25>"
$PN"183"99;
"DQ<24>"
$PN"38"100;
"DQ<23>"
$PN"177"101;
"DQ<22>"
$PN"32"102;
"DQ<21>"
$PN"170"103;
"DQ<20>"
$PN"25"104;
"DQ<19>"
$PN"179"105;
"DQ<18>"
$PN"34"145;
"DQ<16>"
$PN"27"146;
"DQ<14>"
$PN"21"147;
"DQ<13>"
$PN"159"148;
"DQ<12>"
$PN"14"149;
"DQ<11>"
$PN"168"150;
"DQ<10>"
$PN"23"151;
"DQ<9>"
$PN"161"24;
"DQ<8>"
$PN"16"155;
"DQ<7>"
$PN"155"156;
"DQ<6>"
$PN"10"157;
"EVENT_N"
$PN"78"167;
"PAR"
$PN"222"144;
"RESET_N"
$PN"58"143;
"RFU<2>"
$PN"144"173;
"SCL"
$PN"141"171;
"SDA"
$PN"285"170;
"VREFCA"
$PN"146"176;
"CK1P"
$PN"218"127;
"BG<0>"
$PN"63"123;
"BG<1>"
$PN"207"124;
"BA<0>"
$PN"81"125;
"SA<0>"
$PN"139"21;
"VDDSPD"
$PN"284"21;
"SA<2>"
$PN"238"20;
"SA<1>"
$PN"140"21;
"DQ<1>"
$PN"150"154;
"DQ<0>"
$PN"5"158;
"ACT_N"
$PN"62"168;
"ALERT_N"
$PN"208"169;
"A2"
$PN"216"121;
"DQ<35>"
$PN"249"94;
"DQ<36>"
$PN"95"95;
"DQ<38>"
$PN"102"96;
"A10"
$PN"225"111;
"A11"
$PN"210"112;
"A14_WE_N"
$PN"228"66;
"A15_CAS_N"
$PN"86"67;
"A16_RAS_N"
$PN"82"68;
"CB<7>"
$PN"199"140;
"ODT<0>"
$PN"87"136;
"ODT<1>"
$PN"91"134;
"CKE<0>"
$PN"60"135;
"S0_N"
$PN"84"132;
"DQ<27>"
$PN"190"106;
"DQ<26>"
$PN"45"107;
"DQ<15>"
$PN"166"152;
"DQ<17>"
$PN"172"153;
"RFU<0>"
$PN"205"174;
"RFU<1>"
$PN"227"175;
"SAVE_N_NC"
$PN"230"172;
"DQ<57>"
$PN"275"71;
"DQ<58>"
$PN"137"72;
"DQ<54>"
$PN"124"25;
"DQ<53>"
$PN"262"73;
"DQ<52>"
$PN"117"74;
"DQ<51>"
$PN"271"75;
"DQ<50>"
$PN"126"76;
"DQ<49>"
$PN"264"84;
"DQ<48>"
$PN"119"85;
"DQ<47>"
$PN"258"86;
"DQ<2>"
$PN"12"159;
"DQ<3>"
$PN"157"160;
"DQ<4>"
$PN"3"161;
"DQ<5>"
$PN"148"162;
%"TAP"
"6","(2325,3100)","2","mstr_standard","I142";
;
HDL_TAP"TRUE"
BODY_TYPE"PLUMBING"
CDS_LIB"mstr_standard";
"B \NAC \NWC"12;
"S \NAC"
BN"0"57;
%"TAP"
"6","(2325,3200)","2","mstr_standard","I143";
;
HDL_TAP"TRUE"
BODY_TYPE"PLUMBING"
CDS_LIB"mstr_standard";
"B \NAC \NWC"12;
"S \NAC"
BN"1"58;
%"TAP"
"6","(2525,3050)","2","mstr_standard","I144";
;
HDL_TAP"TRUE"
BODY_TYPE"PLUMBING"
CDS_LIB"mstr_standard";
"B \NAC \NWC"11;
"S \NAC"
BN"0"60;
%"TAP"
"6","(2525,3150)","2","mstr_standard","I145";
;
HDL_TAP"TRUE"
BODY_TYPE"PLUMBING"
CDS_LIB"mstr_standard";
"B \NAC \NWC"11;
"S \NAC"
BN"1"53;
%"TAP"
"6","(2325,3300)","2","mstr_standard","I146";
;
HDL_TAP"TRUE"
BODY_TYPE"PLUMBING"
CDS_LIB"mstr_standard";
"B \NAC \NWC"12;
"S \NAC"
BN"2"59;
%"TAP"
"6","(2325,3400)","2","mstr_standard","I147";
;
HDL_TAP"TRUE"
BODY_TYPE"PLUMBING"
CDS_LIB"mstr_standard";
"B \NAC \NWC"12;
"S \NAC"
BN"3"31;
%"TAP"
"6","(2325,3600)","2","mstr_standard","I148";
;
HDL_TAP"TRUE"
BODY_TYPE"PLUMBING"
CDS_LIB"mstr_standard";
"B \NAC \NWC"12;
"S \NAC"
BN"5"50;
%"TAP"
"6","(2325,3500)","2","mstr_standard","I149";
;
HDL_TAP"TRUE"
BODY_TYPE"PLUMBING"
CDS_LIB"mstr_standard";
"B \NAC \NWC"12;
"S \NAC"
BN"4"56;
%"TAP"
"6","(2325,3700)","2","mstr_standard","I150";
;
HDL_TAP"TRUE"
BODY_TYPE"PLUMBING"
CDS_LIB"mstr_standard";
"B \NAC \NWC"12;
"S \NAC"
BN"6"51;
%"TAP"
"6","(2525,3450)","2","mstr_standard","I151";
;
HDL_TAP"TRUE"
BODY_TYPE"PLUMBING"
CDS_LIB"mstr_standard";
"B \NAC \NWC"11;
"S \NAC"
BN"4"30;
%"TAP"
"6","(2525,3350)","2","mstr_standard","I152";
;
HDL_TAP"TRUE"
BODY_TYPE"PLUMBING"
CDS_LIB"mstr_standard";
"B \NAC \NWC"11;
"S \NAC"
BN"3"55;
%"TAP"
"6","(2525,3250)","2","mstr_standard","I153";
;
HDL_TAP"TRUE"
BODY_TYPE"PLUMBING"
CDS_LIB"mstr_standard";
"B \NAC \NWC"11;
"S \NAC"
BN"2"54;
%"TAP"
"6","(2525,3550)","2","mstr_standard","I154";
;
HDL_TAP"TRUE"
BODY_TYPE"PLUMBING"
CDS_LIB"mstr_standard";
"B \NAC \NWC"11;
"S \NAC"
BN"5"29;
%"TAP"
"6","(2525,3650)","2","mstr_standard","I155";
;
HDL_TAP"TRUE"
BODY_TYPE"PLUMBING"
CDS_LIB"mstr_standard";
"B \NAC \NWC"11;
"S \NAC"
BN"6"28;
%"GND"
"1","(4125,950)","2","mstr_symbols","I156";
;
HDL_POWER"GND"
ROOM"DDR4_CH_A"
BODY_TYPE"PLUMBING"
BOM_COST"MEM"
CDS_LIB"mstr_symbols"
SIZE"1B"
VOLTAGE"0";
"A\NAC"18;
%"TAP"
"6","(2325,3800)","2","mstr_standard","I157";
;
HDL_TAP"TRUE"
BODY_TYPE"PLUMBING"
CDS_LIB"mstr_standard";
"B \NAC \NWC"12;
"S \NAC"
BN"7"52;
%"TAP"
"6","(2325,4000)","2","mstr_standard","I158";
;
HDL_TAP"TRUE"
BODY_TYPE"PLUMBING"
CDS_LIB"mstr_standard";
"B \NAC \NWC"12;
"S \NAC"
BN"9"26;
%"TAP"
"6","(2325,3900)","2","mstr_standard","I159";
;
HDL_TAP"TRUE"
BODY_TYPE"PLUMBING"
CDS_LIB"mstr_standard";
"B \NAC \NWC"12;
"S \NAC"
BN"8"49;
%"TAP"
"6","(2325,4100)","2","mstr_standard","I160";
;
HDL_TAP"TRUE"
BODY_TYPE"PLUMBING"
CDS_LIB"mstr_standard";
"B \NAC \NWC"12;
"S \NAC"
BN"10"44;
%"TAP"
"6","(2325,4200)","2","mstr_standard","I161";
;
HDL_TAP"TRUE"
BODY_TYPE"PLUMBING"
CDS_LIB"mstr_standard";
"B \NAC \NWC"12;
"S \NAC"
BN"11"45;
%"TAP"
"6","(2525,3950)","2","mstr_standard","I162";
;
HDL_TAP"TRUE"
BODY_TYPE"PLUMBING"
CDS_LIB"mstr_standard";
"B \NAC \NWC"11;
"S \NAC"
BN"9"48;
%"TAP"
"6","(2525,3850)","2","mstr_standard","I163";
;
HDL_TAP"TRUE"
BODY_TYPE"PLUMBING"
CDS_LIB"mstr_standard";
"B \NAC \NWC"11;
"S \NAC"
BN"8"23;
%"TAP"
"6","(2525,3750)","2","mstr_standard","I164";
;
HDL_TAP"TRUE"
BODY_TYPE"PLUMBING"
CDS_LIB"mstr_standard";
"B \NAC \NWC"11;
"S \NAC"
BN"7"27;
%"TAP"
"6","(2525,4250)","2","mstr_standard","I165";
;
HDL_TAP"TRUE"
BODY_TYPE"PLUMBING"
CDS_LIB"mstr_standard";
"B \NAC \NWC"11;
"S \NAC"
BN"12"37;
%"TAP"
"6","(2525,4050)","2","mstr_standard","I166";
;
HDL_TAP"TRUE"
BODY_TYPE"PLUMBING"
CDS_LIB"mstr_standard";
"B \NAC \NWC"11;
"S \NAC"
BN"10"47;
%"TAP"
"6","(2525,4150)","2","mstr_standard","I167";
;
HDL_TAP"TRUE"
BODY_TYPE"PLUMBING"
CDS_LIB"mstr_standard";
"B \NAC \NWC"11;
"S \NAC"
BN"11"36;
%"TAP"
"6","(2325,4300)","2","mstr_standard","I168";
;
HDL_TAP"TRUE"
BODY_TYPE"PLUMBING"
CDS_LIB"mstr_standard";
"B \NAC \NWC"12;
"S \NAC"
BN"12"46;
%"TAP"
"6","(2325,4500)","2","mstr_standard","I169";
;
HDL_TAP"TRUE"
BODY_TYPE"PLUMBING"
CDS_LIB"mstr_standard";
"B \NAC \NWC"12;
"S \NAC"
BN"14"42;
%"TAP"
"6","(2325,4400)","2","mstr_standard","I170";
;
HDL_TAP"TRUE"
BODY_TYPE"PLUMBING"
CDS_LIB"mstr_standard";
"B \NAC \NWC"12;
"S \NAC"
BN"13"41;
%"TAP"
"6","(2325,4600)","2","mstr_standard","I171";
;
HDL_TAP"TRUE"
BODY_TYPE"PLUMBING"
CDS_LIB"mstr_standard";
"B \NAC \NWC"12;
"S \NAC"
BN"15"43;
%"TAP"
"6","(2325,4700)","2","mstr_standard","I172";
;
HDL_TAP"TRUE"
BODY_TYPE"PLUMBING"
CDS_LIB"mstr_standard";
"B \NAC \NWC"12;
"S \NAC"
BN"16"34;
%"TAP"
"6","(2525,4350)","2","mstr_standard","I173";
;
HDL_TAP"TRUE"
BODY_TYPE"PLUMBING"
CDS_LIB"mstr_standard";
"B \NAC \NWC"11;
"S \NAC"
BN"13"38;
%"TAP"
"6","(2525,4450)","2","mstr_standard","I174";
;
HDL_TAP"TRUE"
BODY_TYPE"PLUMBING"
CDS_LIB"mstr_standard";
"B \NAC \NWC"11;
"S \NAC"
BN"14"39;
%"TAP"
"6","(2525,4750)","2","mstr_standard","I175";
;
HDL_TAP"TRUE"
BODY_TYPE"PLUMBING"
CDS_LIB"mstr_standard";
"B \NAC \NWC"11;
"S \NAC"
BN"17"33;
%"TAP"
"6","(2525,4550)","2","mstr_standard","I176";
;
HDL_TAP"TRUE"
BODY_TYPE"PLUMBING"
CDS_LIB"mstr_standard";
"B \NAC \NWC"11;
"S \NAC"
BN"15"40;
%"TAP"
"6","(2525,4650)","2","mstr_standard","I177";
;
HDL_TAP"TRUE"
BODY_TYPE"PLUMBING"
CDS_LIB"mstr_standard";
"B \NAC \NWC"11;
"S \NAC"
BN"16"32;
%"TAP"
"6","(2325,4800)","2","mstr_standard","I178";
;
HDL_TAP"TRUE"
BODY_TYPE"PLUMBING"
CDS_LIB"mstr_standard";
"B \NAC \NWC"12;
"S \NAC"
BN"17"35;
%"P12V_NVDIMM_ABC"
"1","(2375,2725)","0","mstr_symbols","I181";
;
HDL_POWER"P12V_NVDIMM_ABC"
BODY_TYPE"PLUMBING"
CDS_LIB"mstr_symbols"
VOLTAGE"12.0";
"G\NAC"19;
%"TAP"
"6","(-1575,1900)","0","mstr_standard","I20";
;
HDL_TAP"TRUE"
BODY_TYPE"PLUMBING"
CDS_LIB"mstr_standard";
"B \NAC \NWC"1;
"S \NAC"
BN"1"165;
%"TAP"
"6","(-1575,1850)","0","mstr_standard","I21";
;
HDL_TAP"TRUE"
BODY_TYPE"PLUMBING"
CDS_LIB"mstr_standard";
"B \NAC \NWC"1;
"S \NAC"
BN"0"166;
%"TAP"
"6","(-1575,1950)","0","mstr_standard","I22";
;
HDL_TAP"TRUE"
BODY_TYPE"PLUMBING"
CDS_LIB"mstr_standard";
"B \NAC \NWC"1;
"S \NAC"
BN"2"164;
%"TAP"
"6","(-1575,2000)","0","mstr_standard","I23";
;
HDL_TAP"TRUE"
BODY_TYPE"PLUMBING"
CDS_LIB"mstr_standard";
"B \NAC \NWC"1;
"S \NAC"
BN"3"163;
%"TAP"
"6","(-1575,2050)","0","mstr_standard","I24";
;
HDL_TAP"TRUE"
BODY_TYPE"PLUMBING"
CDS_LIB"mstr_standard";
"B \NAC \NWC"1;
"S \NAC"
BN"4"139;
%"TAP"
"6","(-1575,2150)","0","mstr_standard","I25";
;
HDL_TAP"TRUE"
BODY_TYPE"PLUMBING"
CDS_LIB"mstr_standard";
"B \NAC \NWC"1;
"S \NAC"
BN"6"137;
%"TAP"
"6","(-1575,2100)","0","mstr_standard","I26";
;
HDL_TAP"TRUE"
BODY_TYPE"PLUMBING"
CDS_LIB"mstr_standard";
"B \NAC \NWC"1;
"S \NAC"
BN"5"138;
%"TAP"
"6","(-1575,2200)","0","mstr_standard","I27";
;
HDL_TAP"TRUE"
BODY_TYPE"PLUMBING"
CDS_LIB"mstr_standard";
"B \NAC \NWC"1;
"S \NAC"
BN"7"140;
%"TAP"
"6","(-1575,2350)","0","mstr_standard","I28";
;
HDL_TAP"TRUE"
BODY_TYPE"PLUMBING"
CDS_LIB"mstr_standard";
"B \NAC \NWC"4;
"S \NAC"
BN"3"134;
%"TAP"
"6","(-1575,2300)","0","mstr_standard","I29";
;
HDL_TAP"TRUE"
BODY_TYPE"PLUMBING"
CDS_LIB"mstr_standard";
"B \NAC \NWC"4;
"S \NAC"
BN"2"136;
%"GND"
"1","(-3425,1250)","2","mstr_symbols","I3";
;
HDL_POWER"GND"
ROOM"DDR4_CH_A"
BODY_TYPE"PLUMBING"
BOM_COST"MEM"
CDS_LIB"mstr_symbols"
SIZE"1B"
VOLTAGE"0";
"A\NAC"20;
%"TAP"
"6","(-1575,2450)","0","mstr_standard","I30";
;
HDL_TAP"TRUE"
BODY_TYPE"PLUMBING"
CDS_LIB"mstr_standard";
"B \NAC \NWC"5;
"S \NAC"
BN"2"135;
%"TAP"
"6","(-1575,2650)","0","mstr_standard","I31";
;
HDL_TAP"TRUE"
BODY_TYPE"PLUMBING"
CDS_LIB"mstr_standard";
"B \NAC \NWC"6;
"S \NAC"
BN"5"131;
%"TAP"
"6","(-1575,2600)","0","mstr_standard","I32";
;
HDL_TAP"TRUE"
BODY_TYPE"PLUMBING"
CDS_LIB"mstr_standard";
"B \NAC \NWC"6;
"S \NAC"
BN"4"132;
%"TAP"
"6","(-1575,2500)","0","mstr_standard","I33";
;
HDL_TAP"TRUE"
BODY_TYPE"PLUMBING"
CDS_LIB"mstr_standard";
"B \NAC \NWC"5;
"S \NAC"
BN"3"133;
%"TAP"
"6","(-1575,2700)","0","mstr_standard","I34";
;
HDL_TAP"TRUE"
BODY_TYPE"PLUMBING"
CDS_LIB"mstr_standard";
"B \NAC \NWC"6;
"S \NAC"
BN"6"130;
%"TAP"
"6","(-1775,2900)","0","mstr_standard","I39";
;
HDL_TAP"TRUE"
BODY_TYPE"PLUMBING"
CDS_LIB"mstr_standard";
"B \NAC \NWC"3;
"S \NAC"
BN"2"142;
%"PVPP_ABC"
"1","(-3425,1600)","0","mstr_symbols","I4";
;
HDL_POWER"PVPP_ABC"
ROOM"DDR4_CH_A"
BODY_TYPE"PLUMBING"
CDS_LIB"mstr_symbols"
BOM_COST"MEM"
VOLTAGE"2.5V";
"G\NAC"21;
%"TAP"
"6","(-1775,3000)","0","mstr_standard","I40";
;
HDL_TAP"TRUE"
BODY_TYPE"PLUMBING"
CDS_LIB"mstr_standard";
"B \NAC \NWC"3;
"S \NAC"
BN"3"141;
%"TAP"
"6","(-1575,2750)","0","mstr_standard","I41";
;
HDL_TAP"TRUE"
BODY_TYPE"PLUMBING"
CDS_LIB"mstr_standard";
"B \NAC \NWC"6;
"S \NAC"
BN"7"129;
%"TAP"
"6","(-1575,2950)","0","mstr_standard","I42";
;
HDL_TAP"TRUE"
BODY_TYPE"PLUMBING"
CDS_LIB"mstr_standard";
"B \NAC \NWC"7;
"S \NAC"
BN"2"126;
%"TAP"
"6","(-1575,3150)","0","mstr_standard","I43";
;
HDL_TAP"TRUE"
BODY_TYPE"PLUMBING"
CDS_LIB"mstr_standard";
"B \NAC \NWC"9;
"S \NAC"
BN"0"123;
%"TAP"
"6","(-1575,3200)","0","mstr_standard","I44";
;
HDL_TAP"TRUE"
BODY_TYPE"PLUMBING"
CDS_LIB"mstr_standard";
"B \NAC \NWC"9;
"S \NAC"
BN"1"124;
%"TAP"
"6","(-1575,3050)","0","mstr_standard","I45";
;
HDL_TAP"TRUE"
BODY_TYPE"PLUMBING"
CDS_LIB"mstr_standard";
"B \NAC \NWC"7;
"S \NAC"
BN"3"127;
%"TAP"
"6","(-1575,3450)","0","mstr_standard","I46";
;
HDL_TAP"TRUE"
BODY_TYPE"PLUMBING"
CDS_LIB"mstr_standard";
"B \NAC \NWC"10;
"S \NAC"
BN"1"119;
%"TAP"
"6","(-1575,3400)","0","mstr_standard","I47";
;
HDL_TAP"TRUE"
BODY_TYPE"PLUMBING"
CDS_LIB"mstr_standard";
"B \NAC \NWC"10;
"S \NAC"
BN"0"118;
%"TAP"
"6","(-1575,3250)","0","mstr_standard","I48";
;
HDL_TAP"TRUE"
BODY_TYPE"PLUMBING"
CDS_LIB"mstr_standard";
"B \NAC \NWC"8;
"S \NAC"
BN"0"125;
%"TAP"
"6","(-1575,3300)","0","mstr_standard","I49";
;
HDL_TAP"TRUE"
BODY_TYPE"PLUMBING"
CDS_LIB"mstr_standard";
"B \NAC \NWC"8;
"S \NAC"
BN"1"122;
%"CAP_A"
"1","(-2975,900)","2","dev_discrete","I5";
;
MATERIAL"X7R"
VOLTAGE"25V"
PACK_TYPE"0402V"
TOLERANCE"10%"
VALUE"0.01UF"
PART_NUMBER"A36096-045"
LOCATION"C6U9"
ROOM"DDR4_CH_A"
SEC"1"
SEC_TYPE"0402V"
CDS_SEC"1"
CDS_LIB"dev_discrete"
BOM_COST"MEM"
CDS_LOCATION"C6U9";
"B"
$PN"2"13;
"A"
$PN"1"176;
%"TAP"
"6","(-1575,3500)","0","mstr_standard","I50";
;
HDL_TAP"TRUE"
BODY_TYPE"PLUMBING"
CDS_LIB"mstr_standard";
"B \NAC \NWC"10;
"S \NAC"
BN"2"121;
%"TAP"
"6","(-1575,3550)","0","mstr_standard","I51";
;
HDL_TAP"TRUE"
BODY_TYPE"PLUMBING"
CDS_LIB"mstr_standard";
"B \NAC \NWC"10;
"S \NAC"
BN"3"120;
%"TAP"
"6","(-1575,3700)","0","mstr_standard","I52";
;
HDL_TAP"TRUE"
BODY_TYPE"PLUMBING"
CDS_LIB"mstr_standard";
"B \NAC \NWC"10;
"S \NAC"
BN"6"114;
%"TAP"
"6","(-1575,3650)","0","mstr_standard","I53";
;
HDL_TAP"TRUE"
BODY_TYPE"PLUMBING"
CDS_LIB"mstr_standard";
"B \NAC \NWC"10;
"S \NAC"
BN"5"117;
%"TAP"
"6","(-1575,3600)","0","mstr_standard","I54";
;
HDL_TAP"TRUE"
BODY_TYPE"PLUMBING"
CDS_LIB"mstr_standard";
"B \NAC \NWC"10;
"S \NAC"
BN"4"113;
%"TAP"
"6","(-75,1150)","2","mstr_standard","I55";
;
HDL_TAP"TRUE"
BODY_TYPE"PLUMBING"
CDS_LIB"mstr_standard";
"B \NAC \NWC"2;
"S \NAC"
BN"1"154;
%"TAP"
"6","(-75,1100)","2","mstr_standard","I56";
;
HDL_TAP"TRUE"
BODY_TYPE"PLUMBING"
CDS_LIB"mstr_standard";
"B \NAC \NWC"2;
"S \NAC"
BN"0"158;
%"TAP"
"6","(-75,1250)","2","mstr_standard","I57";
;
HDL_TAP"TRUE"
BODY_TYPE"PLUMBING"
CDS_LIB"mstr_standard";
"B \NAC \NWC"2;
"S \NAC"
BN"3"160;
%"TAP"
"6","(-75,1200)","2","mstr_standard","I58";
;
HDL_TAP"TRUE"
BODY_TYPE"PLUMBING"
CDS_LIB"mstr_standard";
"B \NAC \NWC"2;
"S \NAC"
BN"2"159;
%"TAP"
"6","(-75,1300)","2","mstr_standard","I59";
;
HDL_TAP"TRUE"
BODY_TYPE"PLUMBING"
CDS_LIB"mstr_standard";
"B \NAC \NWC"2;
"S \NAC"
BN"4"161;
%"TAP"
"6","(-75,1400)","2","mstr_standard","I60";
;
HDL_TAP"TRUE"
BODY_TYPE"PLUMBING"
CDS_LIB"mstr_standard";
"B \NAC \NWC"2;
"S \NAC"
BN"6"157;
%"TAP"
"6","(-75,1350)","2","mstr_standard","I61";
;
HDL_TAP"TRUE"
BODY_TYPE"PLUMBING"
CDS_LIB"mstr_standard";
"B \NAC \NWC"2;
"S \NAC"
BN"5"162;
%"TAP"
"6","(-75,1450)","2","mstr_standard","I62";
;
HDL_TAP"TRUE"
BODY_TYPE"PLUMBING"
CDS_LIB"mstr_standard";
"B \NAC \NWC"2;
"S \NAC"
BN"7"156;
%"TAP"
"6","(-75,1550)","2","mstr_standard","I63";
;
HDL_TAP"TRUE"
BODY_TYPE"PLUMBING"
CDS_LIB"mstr_standard";
"B \NAC \NWC"2;
"S \NAC"
BN"9"24;
%"TAP"
"6","(-75,1500)","2","mstr_standard","I64";
;
HDL_TAP"TRUE"
BODY_TYPE"PLUMBING"
CDS_LIB"mstr_standard";
"B \NAC \NWC"2;
"S \NAC"
BN"8"155;
%"TAP"
"6","(-75,1650)","2","mstr_standard","I65";
;
HDL_TAP"TRUE"
BODY_TYPE"PLUMBING"
CDS_LIB"mstr_standard";
"B \NAC \NWC"2;
"S \NAC"
BN"11"150;
%"TAP"
"6","(-75,1600)","2","mstr_standard","I66";
;
HDL_TAP"TRUE"
BODY_TYPE"PLUMBING"
CDS_LIB"mstr_standard";
"B \NAC \NWC"2;
"S \NAC"
BN"10"151;
%"SCONN288_H44441003"
"4","(1675,1650)","0","mstr_sconn","I67";
;
CDS_SEC"4"
MATERIAL"SCONN"
PART_NUMBER"H44441-003"
LOCATION"J6U1"
BOM_SS"NOPOP"
ROOM"DDR4_CH_B"
CDS_LOCATION"J6U1"
SEC"4"
SEC_TYPE"PIP"
CDS_LIB"mstr_sconn"
BOM_COST"MEM"
PACK_TYPE"PIP";
"VDD<0>"
$PN"236"14;
"VDD<6>"
$PN"220"14;
"VDD<10>"
$PN"209"14;
"VDD<13>"
$PN"92"14;
"VDD<16>"
$PN"85"14;
"VDD<19>"
$PN"76"14;
"VDD<23>"
$PN"64"14;
"VDD<25>"
$PN"59"14;
"VTT<0>"
$PN"221"15;
"12V<1>"
$PN"1"19;
"12V<0>"
$PN"145"19;
"VDD<24>"
$PN"61"14;
"VDD<22>"
$PN"67"14;
"VDD<21>"
$PN"70"14;
"VDD<20>"
$PN"73"14;
"VDD<18>"
$PN"80"14;
"VDD<17>"
$PN"83"14;
"VDD<15>"
$PN"88"14;
"VDD<14>"
$PN"90"14;
"VDD<12>"
$PN"204"14;
"VDD<11>"
$PN"206"14;
"VDD<9>"
$PN"212"14;
"VDD<8>"
$PN"215"14;
"VDD<7>"
$PN"217"14;
"VDD<5>"
$PN"223"14;
"VDD<4>"
$PN"226"14;
"VDD<3>"
$PN"229"14;
"VDD<2>"
$PN"231"14;
"VDD<1>"
$PN"233"14;
"VPP<4>"
$PN"142"16;
"VPP<3>"
$PN"143"16;
"VPP<2>"
$PN"288"16;
"VPP<1>"
$PN"286"16;
"VPP<0>"
$PN"287"16;
"VTT<1>"
$PN"77"15;
%"TAP"
"6","(-75,1700)","2","mstr_standard","I68";
;
HDL_TAP"TRUE"
BODY_TYPE"PLUMBING"
CDS_LIB"mstr_standard";
"B \NAC \NWC"2;
"S \NAC"
BN"12"149;
%"TAP"
"6","(-75,1800)","2","mstr_standard","I69";
;
HDL_TAP"TRUE"
BODY_TYPE"PLUMBING"
CDS_LIB"mstr_standard";
"B \NAC \NWC"2;
"S \NAC"
BN"14"147;
%"TAP"
"6","(-75,1750)","2","mstr_standard","I70";
;
HDL_TAP"TRUE"
BODY_TYPE"PLUMBING"
CDS_LIB"mstr_standard";
"B \NAC \NWC"2;
"S \NAC"
BN"13"148;
%"TAP"
"6","(-75,1900)","2","mstr_standard","I71";
;
HDL_TAP"TRUE"
BODY_TYPE"PLUMBING"
CDS_LIB"mstr_standard";
"B \NAC \NWC"2;
"S \NAC"
BN"16"146;
%"TAP"
"6","(-75,1850)","2","mstr_standard","I72";
;
HDL_TAP"TRUE"
BODY_TYPE"PLUMBING"
CDS_LIB"mstr_standard";
"B \NAC \NWC"2;
"S \NAC"
BN"15"152;
%"TAP"
"6","(-75,1950)","2","mstr_standard","I73";
;
HDL_TAP"TRUE"
BODY_TYPE"PLUMBING"
CDS_LIB"mstr_standard";
"B \NAC \NWC"2;
"S \NAC"
BN"17"153;
%"TAP"
"6","(-75,2000)","2","mstr_standard","I74";
;
HDL_TAP"TRUE"
BODY_TYPE"PLUMBING"
CDS_LIB"mstr_standard";
"B \NAC \NWC"2;
"S \NAC"
BN"18"145;
%"TAP"
"6","(-75,2050)","2","mstr_standard","I75";
;
HDL_TAP"TRUE"
BODY_TYPE"PLUMBING"
CDS_LIB"mstr_standard";
"B \NAC \NWC"2;
"S \NAC"
BN"19"105;
%"TAP"
"6","(-75,2100)","2","mstr_standard","I76";
;
HDL_TAP"TRUE"
BODY_TYPE"PLUMBING"
CDS_LIB"mstr_standard";
"B \NAC \NWC"2;
"S \NAC"
BN"20"104;
%"TAP"
"6","(-75,2200)","2","mstr_standard","I77";
;
HDL_TAP"TRUE"
BODY_TYPE"PLUMBING"
CDS_LIB"mstr_standard";
"B \NAC \NWC"2;
"S \NAC"
BN"22"102;
%"TAP"
"6","(-75,2150)","2","mstr_standard","I78";
;
HDL_TAP"TRUE"
BODY_TYPE"PLUMBING"
CDS_LIB"mstr_standard";
"B \NAC \NWC"2;
"S \NAC"
BN"21"103;
%"TAP"
"6","(-75,2250)","2","mstr_standard","I79";
;
HDL_TAP"TRUE"
BODY_TYPE"PLUMBING"
CDS_LIB"mstr_standard";
"B \NAC \NWC"2;
"S \NAC"
BN"23"101;
%"TAP"
"6","(-75,2300)","2","mstr_standard","I80";
;
HDL_TAP"TRUE"
BODY_TYPE"PLUMBING"
CDS_LIB"mstr_standard";
"B \NAC \NWC"2;
"S \NAC"
BN"24"100;
%"TAP"
"6","(-75,2350)","2","mstr_standard","I81";
;
HDL_TAP"TRUE"
BODY_TYPE"PLUMBING"
CDS_LIB"mstr_standard";
"B \NAC \NWC"2;
"S \NAC"
BN"25"99;
%"TAP"
"6","(-75,2400)","2","mstr_standard","I82";
;
HDL_TAP"TRUE"
BODY_TYPE"PLUMBING"
CDS_LIB"mstr_standard";
"B \NAC \NWC"2;
"S \NAC"
BN"26"107;
%"TAP"
"6","(-75,2450)","2","mstr_standard","I83";
;
HDL_TAP"TRUE"
BODY_TYPE"PLUMBING"
CDS_LIB"mstr_standard";
"B \NAC \NWC"2;
"S \NAC"
BN"27"106;
%"TAP"
"6","(-75,2550)","2","mstr_standard","I84";
;
HDL_TAP"TRUE"
BODY_TYPE"PLUMBING"
CDS_LIB"mstr_standard";
"B \NAC \NWC"2;
"S \NAC"
BN"29"97;
%"TAP"
"6","(-75,2500)","2","mstr_standard","I85";
;
HDL_TAP"TRUE"
BODY_TYPE"PLUMBING"
CDS_LIB"mstr_standard";
"B \NAC \NWC"2;
"S \NAC"
BN"28"98;
%"TAP"
"6","(-75,2600)","2","mstr_standard","I86";
;
HDL_TAP"TRUE"
BODY_TYPE"PLUMBING"
CDS_LIB"mstr_standard";
"B \NAC \NWC"2;
"S \NAC"
BN"30"93;
%"TAP"
"6","(-75,2650)","2","mstr_standard","I87";
;
HDL_TAP"TRUE"
BODY_TYPE"PLUMBING"
CDS_LIB"mstr_standard";
"B \NAC \NWC"2;
"S \NAC"
BN"31"92;
%"TAP"
"6","(-75,2700)","2","mstr_standard","I88";
;
HDL_TAP"TRUE"
BODY_TYPE"PLUMBING"
CDS_LIB"mstr_standard";
"B \NAC \NWC"2;
"S \NAC"
BN"32"91;
%"TAP"
"6","(-75,2750)","2","mstr_standard","I89";
;
HDL_TAP"TRUE"
BODY_TYPE"PLUMBING"
CDS_LIB"mstr_standard";
"B \NAC \NWC"2;
"S \NAC"
BN"33"90;
%"TAP"
"6","(-75,2800)","2","mstr_standard","I90";
;
HDL_TAP"TRUE"
BODY_TYPE"PLUMBING"
CDS_LIB"mstr_standard";
"B \NAC \NWC"2;
"S \NAC"
BN"34"89;
%"TAP"
"6","(-75,2850)","2","mstr_standard","I91";
;
HDL_TAP"TRUE"
BODY_TYPE"PLUMBING"
CDS_LIB"mstr_standard";
"B \NAC \NWC"2;
"S \NAC"
BN"35"94;
%"TAP"
"6","(-75,2900)","2","mstr_standard","I92";
;
HDL_TAP"TRUE"
BODY_TYPE"PLUMBING"
CDS_LIB"mstr_standard";
"B \NAC \NWC"2;
"S \NAC"
BN"36"95;
%"TAP"
"6","(-75,2950)","2","mstr_standard","I93";
;
HDL_TAP"TRUE"
BODY_TYPE"PLUMBING"
CDS_LIB"mstr_standard";
"B \NAC \NWC"2;
"S \NAC"
BN"37"88;
%"TAP"
"6","(-75,3100)","2","mstr_standard","I94";
;
HDL_TAP"TRUE"
BODY_TYPE"PLUMBING"
CDS_LIB"mstr_standard";
"B \NAC \NWC"2;
"S \NAC"
BN"40"83;
%"TAP"
"6","(-75,3000)","2","mstr_standard","I95";
;
HDL_TAP"TRUE"
BODY_TYPE"PLUMBING"
CDS_LIB"mstr_standard";
"B \NAC \NWC"2;
"S \NAC"
BN"38"96;
%"TAP"
"6","(-75,3050)","2","mstr_standard","I96";
;
HDL_TAP"TRUE"
BODY_TYPE"PLUMBING"
CDS_LIB"mstr_standard";
"B \NAC \NWC"2;
"S \NAC"
BN"39"87;
%"TAP"
"6","(-75,3200)","2","mstr_standard","I97";
;
HDL_TAP"TRUE"
BODY_TYPE"PLUMBING"
CDS_LIB"mstr_standard";
"B \NAC \NWC"2;
"S \NAC"
BN"42"81;
%"TAP"
"6","(-75,3150)","2","mstr_standard","I98";
;
HDL_TAP"TRUE"
BODY_TYPE"PLUMBING"
CDS_LIB"mstr_standard";
"B \NAC \NWC"2;
"S \NAC"
BN"41"82;
%"TAP"
"6","(-75,3300)","2","mstr_standard","I99";
;
HDL_TAP"TRUE"
BODY_TYPE"PLUMBING"
CDS_LIB"mstr_standard";
"B \NAC \NWC"2;
"S \NAC"
BN"44"79;
END.
